(kicad_pcb
	(version 20241229)
	(generator "pcbnew")
	(generator_version "9.0")
	(general
		(thickness 1.599998)
		(legacy_teardrops no)
	)
	(paper "A4")
	(title_block
		(title "Artix - Datacenter Secure Control Module (DC-SCM)")
		(date "2024-11-06")
		(rev "1.1.3")
		(comment 9 "footprints 251-255 of 544")
	)
	(layers
		(0 "F.Cu" signal)
		(4 "In1.Cu" signal)
		(6 "In2.Cu" signal)
		(8 "In3.Cu" signal)
		(10 "In4.Cu" signal)
		(12 "In5.Cu" signal)
		(14 "In6.Cu" signal)
		(2 "B.Cu" signal)
		(9 "F.Adhes" user "F.Adhesive")
		(11 "B.Adhes" user "B.Adhesive")
		(13 "F.Paste" user)
		(15 "B.Paste" user)
		(5 "F.SilkS" user "F.Silkscreen")
		(7 "B.SilkS" user "B.Silkscreen")
		(1 "F.Mask" user)
		(3 "B.Mask" user)
		(17 "Dwgs.User" user "User.Drawings")
		(19 "Cmts.User" user "User.Comments")
		(21 "Eco1.User" user "User.Eco1")
		(23 "Eco2.User" user "User.Eco2")
		(25 "Edge.Cuts" user)
		(27 "Margin" user)
		(31 "F.CrtYd" user "F.Courtyard")
		(29 "B.CrtYd" user "B.Courtyard")
		(35 "F.Fab" user)
		(33 "B.Fab" user)
	)
	(footprint "antmicro-footprints:R_0402_1005Metric"
		(layer "F.Cu")
		(at 129.375 88.7125 90)
		(descr "Resistor SMD 0402")
		(tags "resistor SMD 0402")
		(property "Reference" "R4"
			(at 0.8125 0.425 90)
			(layer "F.SilkS")
			(effects
				(font
					(size 0.7 0.7)
					(thickness 0.15)
				)
				(justify left bottom)
			)
		)
		(property "Value" "R_10k_0402"
			(at 0 1.4 90)
			(layer "F.Fab")
			(effects
				(font
					(size 0.7 0.7)
					(thickness 0.15)
				)
				(justify left bottom)
			)
		)
		(property "Datasheet" "https://www.bourns.com/docs/product-datasheets/cr.pdf"
			(at 0 0 90)
			(layer "F.Fab")
			(hide yes)
			(effects
				(font
					(size 1.27 1.27)
					(thickness 0.15)
				)
			)
		)
		(property "Description" "SMD Chip Resistor, 10 kohm, ± 1%, 62.5 mW, 0402 [1005 Metric], Thick Film, General Purpose"
			(at 0 0 90)
			(layer "F.Fab")
			(hide yes)
			(effects
				(font
					(size 1.27 1.27)
					(thickness 0.15)
				)
			)
		)
		(property "Author" "Antmicro"
			(at 218.0875 -40.6625 0)
			(layer "F.Fab")
			(hide yes)
			(effects
				(font
					(size 1 1)
					(thickness 0.15)
				)
			)
		)
		(property "License" "Apache-2.0"
			(at 218.0875 -40.6625 0)
			(layer "F.Fab")
			(hide yes)
			(effects
				(font
					(size 1 1)
					(thickness 0.15)
				)
			)
		)
		(property "MPN" "CR0402-FX-1002GLF"
			(at 218.0875 -40.6625 0)
			(layer "F.Fab")
			(hide yes)
			(effects
				(font
					(size 1 1)
					(thickness 0.15)
				)
			)
		)
		(property "Manufacturer" "Bourns"
			(at 218.0875 -40.6625 0)
			(layer "F.Fab")
			(hide yes)
			(effects
				(font
					(size 1 1)
					(thickness 0.15)
				)
			)
		)
		(property "Tolerance" "1%"
			(at 218.0875 -40.6625 0)
			(layer "F.Fab")
			(hide yes)
			(effects
				(font
					(size 1 1)
					(thickness 0.15)
				)
			)
		)
		(property "Val" "10k"
			(at 218.0875 -40.6625 0)
			(layer "F.Fab")
			(hide yes)
			(effects
				(font
					(size 1 1)
					(thickness 0.15)
				)
			)
		)
		(sheetname "/Interfaces/")
		(sheetfile "interfaces.kicad_sch")
		(attr smd)
		(fp_rect
			(start -0.925 -0.47)
			(end 0.925 0.47)
			(stroke
				(width 0.05)
				(type default)
			)
			(fill no)
			(layer "F.CrtYd")
		)
		(fp_rect
			(start -0.5 -0.25)
			(end 0.5 0.25)
			(stroke
				(width 0.15)
				(type solid)
			)
			(fill no)
			(layer "F.Fab")
		)
		(pad "1" smd roundrect
			(at -0.48 0 90)
			(size 0.59 0.64)
			(layers "F.Cu" "F.Mask" "F.Paste")
			(roundrect_rratio 0.25)
			(net 299 "Net-(U19-~{RESET})")
			(pintype "passive")
		)
		(pad "2" smd roundrect
			(at 0.48 0 90)
			(size 0.59 0.64)
			(layers "F.Cu" "F.Mask" "F.Paste")
			(roundrect_rratio 0.25)
			(net 1 "GND")
			(pintype "passive")
		)
	)
	(footprint "antmicro-footprints:R_0402_1005Metric"
		(layer "F.Cu")
		(at 127.45 89.7125 180)
		(descr "Resistor SMD 0402")
		(tags "resistor SMD 0402")
		(property "Reference" "R160"
			(at 0.85 -0.254167 0)
			(layer "F.SilkS")
			(effects
				(font
					(size 0.7 0.7)
					(thickness 0.15)
				)
				(justify right bottom)
			)
		)
		(property "Value" "R_22R_0402"
			(at 0 1.4 0)
			(layer "F.Fab")
			(effects
				(font
					(size 0.7 0.7)
					(thickness 0.15)
				)
				(justify right bottom)
			)
		)
		(property "Datasheet" "https://www.bourns.com/docs/product-datasheets/cr.pdf"
			(at 0 0 180)
			(layer "F.Fab")
			(hide yes)
			(effects
				(font
					(size 1.27 1.27)
					(thickness 0.15)
				)
			)
		)
		(property "Description" "SMD Chip Resistor, 22 ohm, ± 1%, 62.5 mW, 0402 [1005 Metric], Thick Film, General Purpose"
			(at 0 0 180)
			(layer "F.Fab")
			(hide yes)
			(effects
				(font
					(size 1.27 1.27)
					(thickness 0.15)
				)
			)
		)
		(property "Author" "Antmicro"
			(at 254.9 179.425 0)
			(layer "F.Fab")
			(hide yes)
			(effects
				(font
					(size 1 1)
					(thickness 0.15)
				)
			)
		)
		(property "License" "Apache-2.0"
			(at 254.9 179.425 0)
			(layer "F.Fab")
			(hide yes)
			(effects
				(font
					(size 1 1)
					(thickness 0.15)
				)
			)
		)
		(property "MPN" "CR0402-FX-22R0GLF"
			(at 254.9 179.425 0)
			(layer "F.Fab")
			(hide yes)
			(effects
				(font
					(size 1 1)
					(thickness 0.15)
				)
			)
		)
		(property "Manufacturer" "Bourns"
			(at 254.9 179.425 0)
			(layer "F.Fab")
			(hide yes)
			(effects
				(font
					(size 1 1)
					(thickness 0.15)
				)
			)
		)
		(property "Tolerance" "1%"
			(at 254.9 179.425 0)
			(layer "F.Fab")
			(hide yes)
			(effects
				(font
					(size 1 1)
					(thickness 0.15)
				)
			)
		)
		(property "Val" "22R"
			(at 254.9 179.425 0)
			(layer "F.Fab")
			(hide yes)
			(effects
				(font
					(size 1 1)
					(thickness 0.15)
				)
			)
		)
		(sheetname "/Interfaces/")
		(sheetfile "interfaces.kicad_sch")
		(attr smd)
		(fp_rect
			(start -0.925 -0.47)
			(end 0.925 0.47)
			(stroke
				(width 0.05)
				(type default)
			)
			(fill no)
			(layer "F.CrtYd")
		)
		(fp_rect
			(start -0.5 -0.25)
			(end 0.5 0.25)
			(stroke
				(width 0.15)
				(type solid)
			)
			(fill no)
			(layer "F.Fab")
		)
		(pad "1" smd roundrect
			(at -0.48 0 180)
			(size 0.59 0.64)
			(layers "F.Cu" "F.Mask" "F.Paste")
			(roundrect_rratio 0.25)
			(net 346 "Net-(U19-ADBUS0)")
			(pintype "passive")
		)
		(pad "2" smd roundrect
			(at 0.48 0 180)
			(size 0.59 0.64)
			(layers "F.Cu" "F.Mask" "F.Paste")
			(roundrect_rratio 0.25)
			(net 15 "JTAG_TCK")
			(pintype "passive")
		)
	)
	(footprint "antmicro-footprints:R_0402_1005Metric"
		(layer "F.Cu")
		(at 127.45 91.979166 180)
		(descr "Resistor SMD 0402")
		(tags "resistor SMD 0402")
		(property "Reference" "R192"
			(at 0.85 -0.254167 0)
			(layer "F.SilkS")
			(effects
				(font
					(size 0.7 0.7)
					(thickness 0.15)
				)
				(justify right bottom)
			)
		)
		(property "Value" "R_22R_0402"
			(at 0 1.4 0)
			(layer "F.Fab")
			(effects
				(font
					(size 0.7 0.7)
					(thickness 0.15)
				)
				(justify right bottom)
			)
		)
		(property "Datasheet" "https://www.bourns.com/docs/product-datasheets/cr.pdf"
			(at 0 0 180)
			(layer "F.Fab")
			(hide yes)
			(effects
				(font
					(size 1.27 1.27)
					(thickness 0.15)
				)
			)
		)
		(property "Description" "SMD Chip Resistor, 22 ohm, ± 1%, 62.5 mW, 0402 [1005 Metric], Thick Film, General Purpose"
			(at 0 0 180)
			(layer "F.Fab")
			(hide yes)
			(effects
				(font
					(size 1.27 1.27)
					(thickness 0.15)
				)
			)
		)
		(property "Author" "Antmicro"
			(at 254.9 183.958332 0)
			(layer "F.Fab")
			(hide yes)
			(effects
				(font
					(size 1 1)
					(thickness 0.15)
				)
			)
		)
		(property "License" "Apache-2.0"
			(at 254.9 183.958332 0)
			(layer "F.Fab")
			(hide yes)
			(effects
				(font
					(size 1 1)
					(thickness 0.15)
				)
			)
		)
		(property "MPN" "CR0402-FX-22R0GLF"
			(at 254.9 183.958332 0)
			(layer "F.Fab")
			(hide yes)
			(effects
				(font
					(size 1 1)
					(thickness 0.15)
				)
			)
		)
		(property "Manufacturer" "Bourns"
			(at 254.9 183.958332 0)
			(layer "F.Fab")
			(hide yes)
			(effects
				(font
					(size 1 1)
					(thickness 0.15)
				)
			)
		)
		(property "Tolerance" "1%"
			(at 254.9 183.958332 0)
			(layer "F.Fab")
			(hide yes)
			(effects
				(font
					(size 1 1)
					(thickness 0.15)
				)
			)
		)
		(property "Val" "22R"
			(at 254.9 183.958332 0)
			(layer "F.Fab")
			(hide yes)
			(effects
				(font
					(size 1 1)
					(thickness 0.15)
				)
			)
		)
		(sheetname "/Interfaces/")
		(sheetfile "interfaces.kicad_sch")
		(attr smd)
		(fp_rect
			(start -0.925 -0.47)
			(end 0.925 0.47)
			(stroke
				(width 0.05)
				(type default)
			)
			(fill no)
			(layer "F.CrtYd")
		)
		(fp_rect
			(start -0.5 -0.25)
			(end 0.5 0.25)
			(stroke
				(width 0.15)
				(type solid)
			)
			(fill no)
			(layer "F.Fab")
		)
		(pad "1" smd roundrect
			(at -0.48 0 180)
			(size 0.59 0.64)
			(layers "F.Cu" "F.Mask" "F.Paste")
			(roundrect_rratio 0.25)
			(net 349 "Net-(U19-ADBUS2)")
			(pintype "passive")
		)
		(pad "2" smd roundrect
			(at 0.48 0 180)
			(size 0.59 0.64)
			(layers "F.Cu" "F.Mask" "F.Paste")
			(roundrect_rratio 0.25)
			(net 14 "JTAG_TDO")
			(pintype "passive")
		)
	)
	(footprint "antmicro-footprints:TP_SMD_1mm"
		(layer "F.Cu")
		(at 126.25 95.4125)
		(property "Reference" "TP8"
			(at -2.55 0.5875 0)
			(layer "F.SilkS")
			(effects
				(font
					(size 0.7 0.7)
					(thickness 0.15)
				)
				(justify left bottom)
			)
		)
		(property "Value" "TP_1mm_SMD"
			(at 0 1.4 0)
			(layer "F.Fab")
			(effects
				(font
					(size 0.7 0.7)
					(thickness 0.15)
				)
				(justify left bottom)
			)
		)
		(property "Description" "Test point 1mm SMD"
			(at 0 0 0)
			(layer "F.Fab")
			(hide yes)
			(effects
				(font
					(size 1.27 1.27)
					(thickness 0.15)
				)
			)
		)
		(property "Author" "Antmicro"
			(at 0 0 0)
			(layer "F.Fab")
			(hide yes)
			(effects
				(font
					(size 1 1)
					(thickness 0.15)
				)
			)
		)
		(property "License" "Apache-2.0"
			(at 0 0 0)
			(layer "F.Fab")
			(hide yes)
			(effects
				(font
					(size 1 1)
					(thickness 0.15)
				)
			)
		)
		(property "MPN" ""
			(at 0 0 0)
			(layer "F.Fab")
			(hide yes)
			(effects
				(font
					(size 1 1)
					(thickness 0.15)
				)
			)
		)
		(property "Manufacturer" ""
			(at 0 0 0)
			(layer "F.Fab")
			(hide yes)
			(effects
				(font
					(size 1 1)
					(thickness 0.15)
				)
			)
		)
		(sheetname "/Interfaces/")
		(sheetfile "interfaces.kicad_sch")
		(attr exclude_from_pos_files exclude_from_bom)
		(fp_circle
			(center 0 0)
			(end 0.6 0)
			(stroke
				(width 0.05)
				(type default)
			)
			(fill no)
			(layer "F.CrtYd")
		)
		(pad "1" smd circle
			(at 0 0)
			(size 1 1)
			(layers "F.Cu" "F.Mask")
			(net 403 "Net-(U19-ADBUS5)")
			(pinfunction "1")
			(pintype "passive")
		)
	)
	(footprint "antmicro-footprints:Resonator_SMD_Abracon_ABM8G_3.2x2.5mm"
		(layer "F.Cu")
		(at 137.9 86 180)
		(property "Reference" "Y1"
			(at -1.75 -1.75 0)
			(layer "F.SilkS")
			(effects
				(font
					(size 0.7 0.7)
					(thickness 0.15)
				)
				(justify left bottom)
			)
		)
		(property "Value" "Resonator_12MHz_ABM8G"
			(at -1.75 2.548 180)
			(layer "F.Fab")
			(effects
				(font
					(size 0.7 0.7)
					(thickness 0.15)
				)
				(justify left bottom)
			)
		)
		(property "Datasheet" "https://abracon.com/Resonators/ABM8G.pdf"
			(at 0 0 180)
			(layer "F.Fab")
			(hide yes)
			(effects
				(font
					(size 1.27 1.27)
					(thickness 0.15)
				)
			)
		)
		(property "Description" "Crystal, 12 MHz, SMT, 3.2mm x 2.5mm, 30 ppm, 18 pF, 20 ppm, ABM8G"
			(at 0 0 180)
			(layer "F.Fab")
			(hide yes)
			(effects
				(font
					(size 1.27 1.27)
					(thickness 0.15)
				)
			)
		)
		(property "Author" "Antmicro"
			(at 275.8 172 0)
			(layer "F.Fab")
			(hide yes)
			(effects
				(font
					(size 1 1)
					(thickness 0.15)
				)
			)
		)
		(property "License" "Apache-2.0"
			(at 275.8 172 0)
			(layer "F.Fab")
			(hide yes)
			(effects
				(font
					(size 1 1)
					(thickness 0.15)
				)
			)
		)
		(property "MPN" "ABM8G-12.000MHZ-18-D2Y-T"
			(at 275.8 172 0)
			(layer "F.Fab")
			(hide yes)
			(effects
				(font
					(size 1 1)
					(thickness 0.15)
				)
			)
		)
		(property "Manufacturer" "Abracon"
			(at 275.8 172 0)
			(layer "F.Fab")
			(hide yes)
			(effects
				(font
					(size 1 1)
					(thickness 0.15)
				)
			)
		)
		(property "Val" "12 MHz"
			(at 275.8 172 0)
			(layer "F.Fab")
			(hide yes)
			(effects
				(font
					(size 1 1)
					(thickness 0.15)
				)
			)
		)
		(sheetname "/Interfaces/")
		(sheetfile "interfaces.kicad_sch")
		(attr smd)
		(fp_line
			(start 1.6 0.3)
			(end 1.6 -0.2)
			(stroke
				(width 0.15)
				(type solid)
			)
			(layer "F.SilkS")
		)
		(fp_line
			(start -0.35 1.25)
			(end 0.45 1.25)
			(stroke
				(width 0.15)
				(type solid)
			)
			(layer "F.SilkS")
		)
		(fp_line
			(start -0.35 -1.25)
			(end 0.45 -1.25)
			(stroke
				(width 0.15)
				(type solid)
			)
			(layer "F.SilkS")
		)
		(fp_line
			(start -1.6 0.3)
			(end -1.6 -0.2)
			(stroke
				(width 0.15)
				(type solid)
			)
			(layer "F.SilkS")
		)
		(fp_circle
			(center -1.75 1.5)
			(end -1.7 1.5)
			(stroke
				(width 0.15)
				(type solid)
			)
			(fill no)
			(layer "F.SilkS")
		)
		(fp_rect
			(start -1.907 -1.55)
			(end 2.006 1.649)
			(stroke
				(width 0.05)
				(type solid)
			)
			(fill no)
			(layer "F.CrtYd")
		)
		(pad "1" smd roundrect
			(at -1.101 0.949 180)
			(size 1.3 1.1)
			(layers "F.Cu" "F.Mask" "F.Paste")
			(roundrect_rratio 0)
			(chamfer_ratio 0.2)
			(chamfer bottom_left)
			(net 197 "Net-(U19-OSCI)")
			(pintype "passive")
		)
		(pad "2" smd rect
			(at 1.199 0.949 180)
			(size 1.3 1.1)
			(layers "F.Cu" "F.Mask" "F.Paste")
			(net 1 "GND")
			(pinfunction "SH")
			(pintype "passive")
		)
		(pad "3" smd rect
			(at 1.199 -0.85 180)
			(size 1.3 1.1)
			(layers "F.Cu" "F.Mask" "F.Paste")
			(net 198 "Net-(U19-OSCO)")
			(pintype "passive")
		)
		(pad "4" smd rect
			(at -1.101 -0.85 180)
			(size 1.3 1.1)
			(layers "F.Cu" "F.Mask" "F.Paste")
			(net 1 "GND")
			(pinfunction "SH")
			(pintype "passive")
		)
	)
)
